FILE_TYPE = CONNECTIVITY;
{Allegro Design Entry HDL 17.2-2016 S081 (4005846) 1/11/2022}
"PAGE_NUMBER" = 39;
0"NC";
1"GND\g";
2"GND\g";
3"GND\g";
4"GND\g";
5"GND\g";
6"GND\g";
%"SOCKET4677_AZIF0045P001C01CS"
"31","(-1500,1675)","0","pure_quanta","I1";
;
PART_NUMBER"DGA^7000023"
PART_TYPE"SMLF"
MATERIAL"IO"
VALUE"SOCKET4677_AZIF0045-P001C01CS"
$LOCATION"U2"
CDS_LIB"pure_quanta"
NEEDS_NO_SIZE"TRUE"
CDS_LMAN_SYM_OUTLINE"-1050,2150,1050,-2100"
CDS_LOCATION"U2"
$SEC"31"
CDS_SEC"31";
"VSS1312"
$PN"EH42"5;
"VSS1315"
$PN"EH55"5;
"VSS1319"
$PN"EH61"5;
"VSS1320"
$PN"EH67"5;
"VSS1322"
$PN"EH79"5;
"VSS1325"
$PN"EJ11"5;
"VSS1328"
$PN"EJ17"5;
"VSS1331"
$PN"EJ25"5;
"VSS1334"
$PN"EJ35"5;
"VSS1340"
$PN"EJ54"5;
"VSS1343"
$PN"EJ62"5;
"VSS1345"
$PN"EJ68"5;
"VSS1347"
$PN"EJ72"5;
"VSS1355"
$PN"EK16"5;
"VSS1357"
$PN"EK20"5;
"VSS1359"
$PN"EK26"5;
"VSS1366"
$PN"EK44"5;
"VSS1368"
$PN"EK51"5;
"VSS1369"
$PN"EK53"5;
"VSS1371"
$PN"EK59"5;
"VSS1372"
$PN"EK63"5;
"VSS1375"
$PN"EK71"5;
"VSS1377"
$PN"EK77"5;
"VSS1378"
$PN"EK79"5;
"VSS1379"
$PN"EK83"5;
"VSS1380"
$PN"EK89"5;
"VSS1381"
$PN"EL15"5;
"VSS1391"
$PN"EL52"5;
"VSS1394"
$PN"EL58"5;
"VSS1396"
$PN"EL7"5;
"VSS1397"
$PN"EL70"5;
"VSS1398"
$PN"EL72"5;
"VSS1400"
$PN"EL86"6;
"VSS1401"
$PN"EL9"5;
"VSS1405"
$PN"EM49"6;
"VSS1409"
$PN"EM79"6;
"VSS1419"
$PN"EH36"5;
"VSS1421"
$PN"EH49"5;
"VSS1422"
$PN"EH73"5;
"VSS1423"
$PN"EH81"5;
"VSS1424"
$PN"EH83"5;
"VSS1425"
$PN"EJ13"5;
"VSS1426"
$PN"EJ19"5;
"VSS1427"
$PN"EN39"6;
"VSS1428"
$PN"EJ23"5;
"VSS1429"
$PN"EJ29"5;
"VSS1430"
$PN"EJ31"5;
"VSS1431"
$PN"EJ37"5;
"VSS1432"
$PN"EJ41"5;
"VSS1433"
$PN"EJ43"5;
"VSS1434"
$PN"EJ48"5;
"VSS1435"
$PN"EJ50"5;
"VSS1436"
$PN"EN58"6;
"VSS1437"
$PN"EN60"6;
"VSS1438"
$PN"EN62"6;
"VSS1439"
$PN"EJ56"5;
"VSS1440"
$PN"EN66"6;
"VSS1441"
$PN"EN72"6;
"VSS1442"
$PN"EJ60"5;
"VSS1443"
$PN"EJ66"5;
"VSS1444"
$PN"EJ7"5;
"VSS1445"
$PN"EN88"6;
"VSS1446"
$PN"EN9"6;
"VSS1447"
$PN"EJ74"5;
"VSS1448"
$PN"EJ78"5;
"VSS1449"
$PN"EJ88"5;
"VSS1450"
$PN"EJ9"5;
"VSS1451"
$PN"EK10"5;
"VSS1452"
$PN"EP69"6;
"VSS1453"
$PN"EP71"6;
"VSS1454"
$PN"EP77"6;
"VSS1455"
$PN"EK14"5;
"VSS1456"
$PN"ER15"6;
"VSS1457"
$PN"ER21"6;
"VSS1458"
$PN"EK2"5;
"VSS1459"
$PN"EK22"5;
"VSS1460"
$PN"EK28"5;
"VSS1461"
$PN"EK32"5;
"VSS1462"
$PN"ER39"6;
"VSS1463"
$PN"EK34"5;
"VSS1464"
$PN"ER52"6;
"VSS1465"
$PN"EK38"5;
"VSS1466"
$PN"EK4"5;
"VSS1467"
$PN"ER58"6;
"VSS1468"
$PN"ER64"6;
"VSS1469"
$PN"EK40"5;
"VSS1470"
$PN"EK47"5;
"VSS1471"
$PN"EK57"5;
"VSS1472"
$PN"EK65"5;
"VSS1473"
$PN"EK69"5;
"VSS1474"
$PN"EK75"5;
"VSS1475"
$PN"EL21"5;
"VSS1476"
$PN"ER9"6;
"VSS1477"
$PN"EL27"5;
"VSS1478"
$PN"ET14"6;
"VSS1479"
$PN"EL3"5;
"VSS1480"
$PN"ET20"6;
"VSS1481"
$PN"EL33"5;
"VSS1482"
$PN"ET26"6;
"VSS1483"
$PN"EL39"5;
"VSS1484"
$PN"ET32"6;
"VSS1485"
$PN"EL45"5;
"VSS1486"
$PN"EL5"5;
"VSS1488"
$PN"EL64"5;
"VSS1489"
$PN"EL76"5;
"VSS1491"
$PN"ET53"6;
"VSS1492"
$PN"EM42"6;
"VSS1493"
$PN"ET59"6;
"VSS1496"
$PN"EM73"6;
"VSS1497"
$PN"EM8"6;
"VSS1498"
$PN"EM81"6;
"VSS1499"
$PN"EM83"6;
"VSS1500"
$PN"EN11"6;
"VSS1501"
$PN"EN13"6;
"VSS1503"
$PN"EN15"6;
"VSS1505"
$PN"EN17"6;
"VSS1506"
$PN"EN19"6;
"VSS1512"
$PN"EN21"6;
"VSS1513"
$PN"EN23"6;
"VSS1515"
$PN"EN25"6;
"VSS1517"
$PN"EN27"6;
"VSS1518"
$PN"EN29"6;
"VSS1520"
$PN"EN31"6;
"VSS1522"
$PN"EN33"6;
"VSS1524"
$PN"EN35"6;
"VSS1525"
$PN"EN37"6;
"VSS1526"
$PN"EN41"6;
"VSS1528"
$PN"EN43"6;
"VSS1529"
$PN"EN45"6;
"VSS1530"
$PN"EN48"6;
"VSS1531"
$PN"EN50"6;
"VSS1533"
$PN"EN52"6;
"VSS1537"
$PN"EN54"6;
"VSS1539"
$PN"EN56"6;
"VSS1540"
$PN"EN64"6;
"VSS1541"
$PN"EN78"6;
"VSS1542"
$PN"EN80"6;
"VSS1543"
$PN"EP67"6;
"VSS1545"
$PN"EP83"6;
"VSS1547"
$PN"ER27"6;
"VSS1548"
$PN"ER33"6;
"VSS1549"
$PN"ER5"6;
"VSS1550"
$PN"ER7"6;
"VSS1551"
$PN"ER70"6;
"VSS1552"
$PN"ER74"6;
"VSS1553"
$PN"ER78"6;
"VSS1554"
$PN"ER80"6;
"VSS1555"
$PN"ER84"6;
"VSS1556"
$PN"ER86"6;
"VSS1557"
$PN"ET10"6;
"VSS1559"
$PN"ET16"6;
"VSS1561"
$PN"ET22"6;
"VSS1562"
$PN"ET28"6;
"VSS1563"
$PN"ET34"6;
"VSS1565"
$PN"ET38"6;
"VSS1569"
$PN"ET57"6;
"VSS1837"
$PN"ER50"6;
"VSS1836"
$PN"ER48"6;
"VSS1835"
$PN"ER43"6;
"VSS1834"
$PN"ER41"6;
%"SOCKET4677_AZIF0045P001C01CS"
"33","(4575,1675)","0","pure_quanta","I10";
;
PART_NUMBER"DGA^7000023"
PART_TYPE"SMLF"
MATERIAL"IO"
VALUE"SOCKET4677_AZIF0045-P001C01CS"
$LOCATION"U2"
CDS_LIB"pure_quanta"
NEEDS_NO_SIZE"TRUE"
CDS_LMAN_SYM_OUTLINE"-1050,2150,1050,-2100"
CDS_LOCATION"U2"
$SEC"33"
CDS_SEC"33";
"VSS934"
$PN"DM51"1;
"VSS945"
$PN"DM73"1;
"VSS955"
$PN"DN17"1;
"VSS957"
$PN"DN39"1;
"VSS959"
$PN"DN52"1;
"VSS966"
$PN"DP12"1;
"VSS968"
$PN"DP18"1;
"VSS969"
$PN"DP24"1;
"VSS973"
$PN"DP42"1;
"VSS976"
$PN"DP55"1;
"VSS979"
$PN"DP61"1;
"VSS980"
$PN"DP67"1;
"VSS985"
$PN"DP91"1;
"VSS990"
$PN"DR25"1;
"VSS993"
$PN"DR35"1;
"VSS998"
$PN"DR5"1;
"VSS1000"
$PN"DR54"1;
"VSS1002"
$PN"DR60"1;
"VSS1003"
$PN"DR62"1;
"VSS1005"
$PN"DR68"1;
"VSS1006"
$PN"DR72"1;
"VSS1013"
$PN"DT16"2;
"VSS1014"
$PN"DT20"2;
"VSS1016"
$PN"DT26"2;
"VSS1021"
$PN"DT4"2;
"VSS1023"
$PN"DT44"2;
"VSS1025"
$PN"DT51"2;
"VSS1026"
$PN"DT53"2;
"VSS1028"
$PN"DT59"2;
"VSS1029"
$PN"DT63"2;
"VSS1036"
$PN"DT83"2;
"VSS1047"
$PN"DU39"2;
"VSS1048"
$PN"DU45"2;
"VSS1050"
$PN"DU52"2;
"VSS1051"
$PN"DU58"2;
"VSS1052"
$PN"DU64"2;
"VSS1054"
$PN"DU70"2;
"VSS1059"
$PN"DV12"2;
"VSS1060"
$PN"DV16"2;
"VSS1063"
$PN"DV4"2;
"VSS1064"
$PN"DV42"2;
"VSS1077"
$PN"DW21"2;
"VSS1097"
$PN"DW60"2;
"VSS1100"
$PN"DM12"1;
"VSS1101"
$PN"DM16"1;
"VSS1102"
$PN"DM18"1;
"VSS1103"
$PN"DM20"1;
"VSS1104"
$PN"DM22"1;
"VSS1105"
$PN"DM24"1;
"VSS1106"
$PN"DM26"1;
"VSS1107"
$PN"DM28"1;
"VSS1108"
$PN"DM30"1;
"VSS1109"
$PN"DM32"1;
"VSS1110"
$PN"DM34"1;
"VSS1113"
$PN"DM36"1;
"VSS1114"
$PN"DM38"1;
"VSS1117"
$PN"DM4"1;
"VSS1118"
$PN"DM40"1;
"VSS1119"
$PN"DM42"1;
"VSS1120"
$PN"DM44"1;
"VSS1121"
$PN"DM47"1;
"VSS1122"
$PN"DM49"1;
"VSS1123"
$PN"DM53"1;
"VSS1124"
$PN"DM55"1;
"VSS1127"
$PN"DM57"1;
"VSS1128"
$PN"DM59"1;
"VSS1130"
$PN"DM61"1;
"VSS1132"
$PN"DM63"1;
"VSS1133"
$PN"DM65"1;
"VSS1134"
$PN"DM67"1;
"VSS1135"
$PN"DM69"1;
"VSS1136"
$PN"DM71"1;
"VSS1137"
$PN"DM75"1;
"VSS1138"
$PN"DM77"1;
"VSS1139"
$PN"DM79"1;
"VSS1140"
$PN"DM8"1;
"VSS1143"
$PN"DN78"1;
"VSS1147"
$PN"DN84"1;
"VSS1148"
$PN"DN88"1;
"VSS1149"
$PN"DP16"1;
"VSS1150"
$PN"DP30"1;
"VSS1151"
$PN"DP36"1;
"VSS1152"
$PN"DP4"1;
"VSS1153"
$PN"DP49"1;
"VSS1154"
$PN"DP73"1;
"VSS1157"
$PN"DP8"1;
"VSS1159"
$PN"DP81"1;
"VSS1160"
$PN"DP87"1;
"VSS1162"
$PN"DR1"1;
"VSS1164"
$PN"DR13"1;
"VSS1166"
$PN"DR19"1;
"VSS1169"
$PN"DR23"1;
"VSS1172"
$PN"DR29"1;
"VSS1173"
$PN"DR31"1;
"VSS1174"
$PN"DR37"1;
"VSS1175"
$PN"DR41"1;
"VSS1176"
$PN"DR43"1;
"VSS1177"
$PN"DR48"1;
"VSS1178"
$PN"DR50"1;
"VSS1179"
$PN"DR56"1;
"VSS1181"
$PN"DR66"1;
"VSS1182"
$PN"DR74"2;
"VSS1183"
$PN"DR78"2;
"VSS1184"
$PN"DR84"2;
"VSS1186"
$PN"DR88"2;
"VSS1187"
$PN"DR9"1;
"VSS1189"
$PN"DT12"2;
"VSS1190"
$PN"DT22"2;
"VSS1191"
$PN"DT28"2;
"VSS1192"
$PN"DT32"2;
"VSS1194"
$PN"DT34"2;
"VSS1196"
$PN"DT38"2;
"VSS1199"
$PN"DT40"2;
"VSS1201"
$PN"DT47"2;
"VSS1202"
$PN"DT57"2;
"VSS1203"
$PN"DT65"2;
"VSS1204"
$PN"DT69"2;
"VSS1205"
$PN"DT71"2;
"VSS1206"
$PN"DT75"2;
"VSS1207"
$PN"DT8"2;
"VSS1209"
$PN"DU21"2;
"VSS1211"
$PN"DU27"2;
"VSS1212"
$PN"DU33"2;
"VSS1213"
$PN"DU76"2;
"VSS1214"
$PN"DU78"2;
"VSS1215"
$PN"DU84"2;
"VSS1216"
$PN"DU88"2;
"VSS1218"
$PN"DV77"2;
"VSS1219"
$PN"DV79"2;
"VSS1221"
$PN"DV8"2;
"VSS1222"
$PN"DV81"2;
"VSS1226"
$PN"DV83"2;
"VSS1227"
$PN"DV87"2;
"VSS1228"
$PN"DV91"2;
"VSS1229"
$PN"DW1"2;
"VSS1230"
$PN"DW13"2;
"VSS1231"
$PN"DW17"2;
"VSS1233"
$PN"DW19"2;
"VSS1234"
$PN"DW23"2;
"VSS1236"
$PN"DW25"2;
"VSS1238"
$PN"DW27"2;
"VSS1239"
$PN"DW29"2;
"VSS1240"
$PN"DW31"2;
"VSS1241"
$PN"DW33"2;
"VSS1242"
$PN"DW35"2;
"VSS1243"
$PN"DW37"2;
"VSS1244"
$PN"DW39"2;
"VSS1245"
$PN"DW41"2;
"VSS1246"
$PN"DW43"2;
"VSS1247"
$PN"DW45"2;
"VSS1248"
$PN"DW48"2;
"VSS1249"
$PN"DW5"2;
"VSS1250"
$PN"DW50"2;
"VSS1251"
$PN"DW52"2;
"VSS1252"
$PN"DW54"2;
"VSS1253"
$PN"DW56"2;
"VSS1254"
$PN"DW58"2;
"VSS1255"
$PN"DW62"2;
"VSS1256"
$PN"DW64"2;
"VSS1268"
$PN"DW9"2;
%"UNIVERSAL_GND"
"1","(-2950,-850)","0","logical_power","I2";
;
CDS_LIB"logical_power"
HDL_POWER"GND";
"A"6;
%"UNIVERSAL_GND"
"1","(-50,-850)","0","logical_power","I3";
;
CDS_LIB"logical_power"
HDL_POWER"GND";
"A"5;
%"UNIVERSAL_GND"
"1","(3000,-850)","0","logical_power","I5";
;
CDS_LIB"logical_power"
HDL_POWER"GND";
"A"4;
%"UNIVERSAL_GND"
"1","(100,-850)","0","logical_power","I6";
;
CDS_LIB"logical_power"
HDL_POWER"GND";
"A"3;
%"UNIVERSAL_GND"
"1","(3125,-850)","0","logical_power","I7";
;
CDS_LIB"logical_power"
HDL_POWER"GND";
"A"2;
%"UNIVERSAL_GND"
"1","(6025,-850)","0","logical_power","I8";
;
CDS_LIB"logical_power"
HDL_POWER"GND";
"A"1;
%"SOCKET4677_AZIF0045P001C01CS"
"32","(1550,1675)","0","pure_quanta","I9";
;
PART_NUMBER"DGA^7000023"
PART_TYPE"SMLF"
MATERIAL"IO"
VALUE"SOCKET4677_AZIF0045-P001C01CS"
$LOCATION"U2"
CDS_LIB"pure_quanta"
NEEDS_NO_SIZE"TRUE"
CDS_LMAN_SYM_OUTLINE"-1050,2150,1050,-2100"
CDS_LOCATION"U2"
$SEC"32"
CDS_SEC"32";
"VSS1111"
$PN"DY12"4;
"VSS1112"
$PN"DY16"4;
"VSS1115"
$PN"DY4"4;
"VSS1116"
$PN"DY42"4;
"VSS1141"
$PN"EA39"4;
"VSS1142"
$PN"EA45"4;
"VSS1144"
$PN"EA52"4;
"VSS1145"
$PN"EA58"4;
"VSS1146"
$PN"EA64"4;
"VSS1155"
$PN"EB16"4;
"VSS1156"
$PN"EB20"4;
"VSS1158"
$PN"EB26"4;
"VSS1161"
$PN"EB34"4;
"VSS1163"
$PN"EB4"4;
"VSS1165"
$PN"EB44"4;
"VSS1167"
$PN"EB51"4;
"VSS1168"
$PN"EB53"4;
"VSS1170"
$PN"EB59"4;
"VSS1171"
$PN"EB63"4;
"VSS1180"
$PN"EB91"4;
"VSS1185"
$PN"EC25"4;
"VSS1188"
$PN"EC35"4;
"VSS1193"
$PN"EC5"4;
"VSS1195"
$PN"EC54"4;
"VSS1197"
$PN"EC60"4;
"VSS1198"
$PN"EC62"4;
"VSS1200"
$PN"EC68"4;
"VSS1208"
$PN"ED12"3;
"VSS1210"
$PN"ED18"3;
"VSS1217"
$PN"ED42"3;
"VSS1220"
$PN"ED55"3;
"VSS1223"
$PN"ED61"3;
"VSS1224"
$PN"ED67"3;
"VSS1225"
$PN"ED73"3;
"VSS1232"
$PN"EE17"3;
"VSS1235"
$PN"EE39"3;
"VSS1237"
$PN"EE52"3;
"VSS1257"
$PN"DW66"4;
"VSS1258"
$PN"DW68"4;
"VSS1259"
$PN"DW70"4;
"VSS1260"
$PN"DW72"4;
"VSS1261"
$PN"DW74"4;
"VSS1262"
$PN"DW76"4;
"VSS1263"
$PN"DW80"4;
"VSS1264"
$PN"DW82"4;
"VSS1265"
$PN"EF51"3;
"VSS1266"
$PN"DW84"4;
"VSS1267"
$PN"DW88"4;
"VSS1269"
$PN"DY77"4;
"VSS1270"
$PN"DY8"4;
"VSS1274"
$PN"EA21"4;
"VSS1275"
$PN"EA27"4;
"VSS1276"
$PN"EF73"3;
"VSS1277"
$PN"EF75"3;
"VSS1278"
$PN"EA33"4;
"VSS1279"
$PN"EA70"4;
"VSS1280"
$PN"EA76"4;
"VSS1281"
$PN"EA78"4;
"VSS1282"
$PN"EA80"4;
"VSS1283"
$PN"EF89"3;
"VSS1284"
$PN"EG13"3;
"VSS1285"
$PN"EA84"4;
"VSS1286"
$PN"EA88"4;
"VSS1287"
$PN"EB12"4;
"VSS1288"
$PN"EB22"4;
"VSS1289"
$PN"EB28"4;
"VSS1290"
$PN"EG5"3;
"VSS1291"
$PN"EG52"3;
"VSS1292"
$PN"EB32"4;
"VSS1293"
$PN"EB38"4;
"VSS1294"
$PN"EG7"3;
"VSS1295"
$PN"EB40"4;
"VSS1296"
$PN"EB47"4;
"VSS1297"
$PN"EB57"4;
"VSS1298"
$PN"EB65"4;
"VSS1299"
$PN"EB69"4;
"VSS1300"
$PN"EB71"4;
"VSS1301"
$PN"EB75"4;
"VSS1302"
$PN"EH12"3;
"VSS1303"
$PN"EH14"3;
"VSS1304"
$PN"EB79"4;
"VSS1305"
$PN"EH18"3;
"VSS1306"
$PN"EB8"4;
"VSS1307"
$PN"EB83"4;
"VSS1308"
$PN"EB87"4;
"VSS1309"
$PN"EC1"4;
"VSS1310"
$PN"EC13"4;
"VSS1311"
$PN"EC19"4;
"VSS1313"
$PN"EC23"4;
"VSS1314"
$PN"EC29"4;
"VSS1316"
$PN"EC31"4;
"VSS1317"
$PN"EC37"4;
"VSS1318"
$PN"EH6"3;
"VSS1321"
$PN"EC41"4;
"VSS1323"
$PN"EC43"4;
"VSS1324"
$PN"EC48"4;
"VSS1326"
$PN"EC50"4;
"VSS1327"
$PN"EC56"4;
"VSS1329"
$PN"EC66"4;
"VSS1330"
$PN"EC72"4;
"VSS1332"
$PN"EC74"4;
"VSS1333"
$PN"EC82"3;
"VSS1335"
$PN"EC84"3;
"VSS1336"
$PN"EC88"3;
"VSS1337"
$PN"EC9"4;
"VSS1338"
$PN"ED16"3;
"VSS1339"
$PN"ED24"3;
"VSS1341"
$PN"ED30"3;
"VSS1342"
$PN"ED36"3;
"VSS1344"
$PN"ED4"3;
"VSS1346"
$PN"ED49"3;
"VSS1348"
$PN"ED8"3;
"VSS1349"
$PN"EE78"3;
"VSS1350"
$PN"EE80"3;
"VSS1351"
$PN"EE88"3;
"VSS1352"
$PN"EF12"3;
"VSS1353"
$PN"EF16"3;
"VSS1354"
$PN"EF18"3;
"VSS1356"
$PN"EF2"3;
"VSS1358"
$PN"EF20"3;
"VSS1360"
$PN"EF22"3;
"VSS1361"
$PN"EF24"3;
"VSS1362"
$PN"EF26"3;
"VSS1363"
$PN"EF28"3;
"VSS1364"
$PN"EF30"3;
"VSS1365"
$PN"EF32"3;
"VSS1367"
$PN"EF34"3;
"VSS1370"
$PN"EF36"3;
"VSS1373"
$PN"EF38"3;
"VSS1374"
$PN"EF4"3;
"VSS1376"
$PN"EF40"3;
"VSS1382"
$PN"EF42"3;
"VSS1383"
$PN"EF44"3;
"VSS1384"
$PN"EF47"3;
"VSS1385"
$PN"EF49"3;
"VSS1386"
$PN"EF53"3;
"VSS1387"
$PN"EF55"3;
"VSS1388"
$PN"EF57"3;
"VSS1389"
$PN"EF59"3;
"VSS1390"
$PN"EF61"3;
"VSS1392"
$PN"EF63"3;
"VSS1393"
$PN"EF65"3;
"VSS1395"
$PN"EF67"3;
"VSS1399"
$PN"EF69"3;
"VSS1402"
$PN"EF71"3;
"VSS1403"
$PN"EF77"3;
"VSS1404"
$PN"EF8"3;
"VSS1406"
$PN"EF85"3;
"VSS1407"
$PN"EF87"3;
"VSS1408"
$PN"EG39"3;
"VSS1410"
$PN"EG82"3;
"VSS1411"
$PN"EG84"3;
"VSS1412"
$PN"EG86"3;
"VSS1413"
$PN"EG88"3;
"VSS1414"
$PN"EG9"3;
"VSS1415"
$PN"EG90"3;
"VSS1416"
$PN"EH16"3;
"VSS1417"
$PN"EH24"3;
"VSS1418"
$PN"EH30"3;
"VSS1420"
$PN"EH4"3;
END.
